# S9S_MB_2U (Grand Teton) — schematic netlist excerpt (pin names and nets, part order shuffled) for the footprints in the layout excerpt that follows; sources: Cadence DE-HDL packaged netlist, KiCad conversion of 03242023_DA0F0TMBIJ0_F0T_Motherboard_J_brd_V01_OCP.brd

R4588  Q_RES  1K 1% EMPTY  pkg 0402LF  page 195 : A = FAB_BMC_REV_ID2 ; B = GND
PL44  Q_INDUCTOR  100NH/16A IND  pkg SMLF  page 271 : \1\ = P12V_AUX ; \2\ = SW_P12V_PVCCFA_EHV_FIVRA_CPU0_L
R481  Q_RES  0 5% CHIP  pkg 0402LF  page 239 : A = JTAG_DBP_TDI ; B = JTAG_DBP_FB_TDI

(kicad_pcb
	(version 20260206)
	(generator "pcbnew")
	(generator_version "10.0")
	(general
		(thickness 1.6)
		(legacy_teardrops no)
	)
	(paper "A4")
	(title_block
		(title "03242023_DA0F0TMBIJ0_F0T_Motherboard_J_brd_V01_OCP.brd")
		(comment 1 "Grand Teton / footprints 2421-2423 of 6105")
	)
	(layers
		(0 "F.Cu" signal "TOP")
		(4 "In1.Cu" signal "GND")
		(6 "In2.Cu" signal "IN1")
		(8 "In3.Cu" signal "GND1")
		(10 "In4.Cu" signal "IN2")
		(12 "In5.Cu" signal "GND2")
		(14 "In6.Cu" signal "IN3")
		(16 "In7.Cu" signal "GND3")
		(18 "In8.Cu" signal "VCC")
		(20 "In9.Cu" signal "VCC1")
		(22 "In10.Cu" signal "GND4")
		(24 "In11.Cu" signal "IN4")
		(26 "In12.Cu" signal "GND5")
		(28 "In13.Cu" signal "IN5")
		(30 "In14.Cu" signal "GND6")
		(32 "In15.Cu" signal "IN6")
		(34 "In16.Cu" signal "GND7")
		(2 "B.Cu" signal "BOTTOM")
		(9 "F.Adhes" user "F.Adhesive")
		(11 "B.Adhes" user "B.Adhesive")
		(13 "F.Paste" user "Package Geometry/Pastemask Top")
		(15 "B.Paste" user "Package Geometry/Pastemask Bottom")
		(5 "F.SilkS" user "Ref Des/Silkscreen Top")
		(7 "B.SilkS" user "Ref Des/Silkscreen Bottom")
		(1 "F.Mask" user "Board Geometry/Soldermask Top")
		(3 "B.Mask" user "Board Geometry/Soldermask Bottom")
		(17 "Dwgs.User" user "User.Drawings")
		(19 "Cmts.User" user "User.Comments")
		(21 "Eco1.User" user "User.Eco1")
		(23 "Eco2.User" user "User.Eco2")
		(25 "Edge.Cuts" user "Board Geometry/Outline")
		(27 "Margin" user)
		(31 "F.CrtYd" user "Package Geometry/Place Bound Top")
		(29 "B.CrtYd" user "Package Geometry/Place Bound Bottom")
		(35 "F.Fab" user "Ref Des/Assembly Top")
		(33 "B.Fab" user "Ref Des/Assembly Bottom")
	)
	(footprint ""
		(layer "F.Cu")
		(at 176.6824 -94.338648 90)
		(property "Reference" "R4588"
			(at 0 0 90)
			(layer "F.SilkS")
			(hide yes)
			(effects
				(font
					(size 1.27 1.27)
				)
			)
		)
		(property "Value" ""
			(at 0 0 90)
			(layer "F.Fab")
			(effects
				(font
					(size 1.27 1.27)
				)
			)
		)
		(duplicate_pad_numbers_are_jumpers no)
		(fp_line
			(start 0.7874 -0.4064)
			(end 0.7874 0.4064)
			(stroke
				(width 0.1524)
				(type default)
			)
			(layer "F.SilkS")
		)
		(fp_line
			(start -0.7874 -0.4064)
			(end 0.7874 -0.4064)
			(stroke
				(width 0.1524)
				(type default)
			)
			(layer "F.SilkS")
		)
		(fp_line
			(start 0.7874 0.4064)
			(end -0.7874 0.4064)
			(stroke
				(width 0.1524)
				(type default)
			)
			(layer "F.SilkS")
		)
		(fp_line
			(start -0.7874 0.4064)
			(end -0.7874 -0.4064)
			(stroke
				(width 0.1524)
				(type default)
			)
			(layer "F.SilkS")
		)
		(fp_line
			(start -0.12065 -0.305054)
			(end -0.12065 -0.2794)
			(stroke
				(width 0.1)
				(type default)
			)
			(layer "F.Fab")
		)
		(fp_line
			(start -0.67945 -0.305054)
			(end -0.12065 -0.305054)
			(stroke
				(width 0.1)
				(type default)
			)
			(layer "F.Fab")
		)
		(fp_line
			(start 0.67945 -0.3048)
			(end 0.67945 0.3048)
			(stroke
				(width 0.1)
				(type default)
			)
			(layer "F.Fab")
		)
		(fp_line
			(start 0.12065 -0.3048)
			(end 0.67945 -0.3048)
			(stroke
				(width 0.1)
				(type default)
			)
			(layer "F.Fab")
		)
		(fp_line
			(start 0.12065 -0.2794)
			(end 0.12065 -0.3048)
			(stroke
				(width 0.1)
				(type default)
			)
			(layer "F.Fab")
		)
		(fp_line
			(start -0.12065 -0.2794)
			(end 0.12065 -0.2794)
			(stroke
				(width 0.1)
				(type default)
			)
			(layer "F.Fab")
		)
		(fp_line
			(start 0.120396 0.2794)
			(end -0.12065 0.2794)
			(stroke
				(width 0.1)
				(type default)
			)
			(layer "F.Fab")
		)
		(fp_line
			(start -0.12065 0.2794)
			(end -0.12065 0.3048)
			(stroke
				(width 0.1)
				(type default)
			)
			(layer "F.Fab")
		)
		(fp_line
			(start 0.67945 0.3048)
			(end 0.120396 0.3048)
			(stroke
				(width 0.1)
				(type default)
			)
			(layer "F.Fab")
		)
		(fp_line
			(start 0.120396 0.3048)
			(end 0.120396 0.2794)
			(stroke
				(width 0.1)
				(type default)
			)
			(layer "F.Fab")
		)
		(fp_line
			(start -0.12065 0.3048)
			(end -0.67945 0.3048)
			(stroke
				(width 0.1)
				(type default)
			)
			(layer "F.Fab")
		)
		(fp_line
			(start -0.67945 0.3048)
			(end -0.67945 -0.305054)
			(stroke
				(width 0.1)
				(type default)
			)
			(layer "F.Fab")
		)
		(pad "1" smd rect
			(at -0.40005 0 270)
			(size 0.4572 0.508)
			(layers "F.Cu" "F.Mask" "F.Paste")
			(net "FAB_BMC_REV_ID2")
		)
		(pad "2" smd rect
			(at 0.40005 0 270)
			(size 0.4572 0.508)
			(layers "F.Cu" "F.Mask" "F.Paste")
			(net "GND")
		)
	)
	(footprint ""
		(layer "F.Cu")
		(at 290.874704 -372.471188)
		(property "Reference" "PL44"
			(at -1.46812 -4.415028 0)
			(unlocked yes)
			(layer "F.SilkS")
			(effects
				(font
					(size 0.7874 0.5842)
					(thickness 0.1524)
				)
				(justify left)
			)
		)
		(property "Value" ""
			(at 0 0 0)
			(layer "F.Fab")
			(effects
				(font
					(size 1.27 1.27)
				)
			)
		)
		(duplicate_pad_numbers_are_jumpers no)
		(fp_line
			(start -2.249932 -2.249932)
			(end 2.249932 -2.249932)
			(stroke
				(width 0.1524)
				(type default)
			)
			(layer "F.SilkS")
		)
		(fp_line
			(start -2.249932 -1.3843)
			(end -2.249932 -2.249932)
			(stroke
				(width 0.1524)
				(type default)
			)
			(layer "F.SilkS")
		)
		(fp_line
			(start -2.249932 2.249932)
			(end -2.249932 1.3843)
			(stroke
				(width 0.1524)
				(type default)
			)
			(layer "F.SilkS")
		)
		(fp_line
			(start 2.249932 -2.249932)
			(end 2.249932 -1.3843)
			(stroke
				(width 0.1524)
				(type default)
			)
			(layer "F.SilkS")
		)
		(fp_line
			(start 2.249932 1.3843)
			(end 2.249932 2.249932)
			(stroke
				(width 0.1524)
				(type default)
			)
			(layer "F.SilkS")
		)
		(fp_line
			(start 2.249932 2.249932)
			(end -2.249932 2.249932)
			(stroke
				(width 0.1524)
				(type default)
			)
			(layer "F.SilkS")
		)
		(fp_line
			(start -2.249932 -2.249932)
			(end 2.249932 -2.249932)
			(stroke
				(width 0.1)
				(type default)
			)
			(layer "F.Fab")
		)
		(fp_line
			(start -2.249932 2.249932)
			(end -2.249932 -2.249932)
			(stroke
				(width 0.1)
				(type default)
			)
			(layer "F.Fab")
		)
		(fp_line
			(start 2.249932 -2.249932)
			(end 2.249932 2.249932)
			(stroke
				(width 0.1)
				(type default)
			)
			(layer "F.Fab")
		)
		(fp_line
			(start 2.249932 2.249932)
			(end -2.249932 2.249932)
			(stroke
				(width 0.1)
				(type default)
			)
			(layer "F.Fab")
		)
		(pad "1" smd rect
			(at -1.82499 0)
			(size 1.0668 2.5146)
			(layers "F.Cu" "F.Mask" "F.Paste")
			(net "P12V_AUX")
		)
		(pad "2" smd rect
			(at 1.82499 0)
			(size 1.0668 2.5146)
			(layers "F.Cu" "F.Mask" "F.Paste")
			(net "SW_P12V_PVCCFA_EHV_FIVRA_CPU0_L")
		)
	)
	(footprint ""
		(layer "F.Cu")
		(at 372.561358 -92.962984 90)
		(property "Reference" "R481"
			(at 0 0 90)
			(layer "F.SilkS")
			(hide yes)
			(effects
				(font
					(size 1.27 1.27)
				)
			)
		)
		(property "Value" ""
			(at 0 0 90)
			(layer "F.Fab")
			(effects
				(font
					(size 1.27 1.27)
				)
			)
		)
		(duplicate_pad_numbers_are_jumpers no)
		(fp_line
			(start 0.7874 -0.4064)
			(end 0.7874 0.4064)
			(stroke
				(width 0.1524)
				(type default)
			)
			(layer "F.SilkS")
		)
		(fp_line
			(start -0.7874 -0.4064)
			(end 0.7874 -0.4064)
			(stroke
				(width 0.1524)
				(type default)
			)
			(layer "F.SilkS")
		)
		(fp_line
			(start 0.7874 0.4064)
			(end -0.7874 0.4064)
			(stroke
				(width 0.1524)
				(type default)
			)
			(layer "F.SilkS")
		)
		(fp_line
			(start -0.7874 0.4064)
			(end -0.7874 -0.4064)
			(stroke
				(width 0.1524)
				(type default)
			)
			(layer "F.SilkS")
		)
		(fp_line
			(start -0.12065 -0.305054)
			(end -0.12065 -0.2794)
			(stroke
				(width 0.1)
				(type default)
			)
			(layer "F.Fab")
		)
		(fp_line
			(start -0.67945 -0.305054)
			(end -0.12065 -0.305054)
			(stroke
				(width 0.1)
				(type default)
			)
			(layer "F.Fab")
		)
		(fp_line
			(start 0.67945 -0.3048)
			(end 0.67945 0.3048)
			(stroke
				(width 0.1)
				(type default)
			)
			(layer "F.Fab")
		)
		(fp_line
			(start 0.12065 -0.3048)
			(end 0.67945 -0.3048)
			(stroke
				(width 0.1)
				(type default)
			)
			(layer "F.Fab")
		)
		(fp_line
			(start 0.12065 -0.2794)
			(end 0.12065 -0.3048)
			(stroke
				(width 0.1)
				(type default)
			)
			(layer "F.Fab")
		)
		(fp_line
			(start -0.12065 -0.2794)
			(end 0.12065 -0.2794)
			(stroke
				(width 0.1)
				(type default)
			)
			(layer "F.Fab")
		)
		(fp_line
			(start 0.120396 0.2794)
			(end -0.12065 0.2794)
			(stroke
				(width 0.1)
				(type default)
			)
			(layer "F.Fab")
		)
		(fp_line
			(start -0.12065 0.2794)
			(end -0.12065 0.3048)
			(stroke
				(width 0.1)
				(type default)
			)
			(layer "F.Fab")
		)
		(fp_line
			(start 0.67945 0.3048)
			(end 0.120396 0.3048)
			(stroke
				(width 0.1)
				(type default)
			)
			(layer "F.Fab")
		)
		(fp_line
			(start 0.120396 0.3048)
			(end 0.120396 0.2794)
			(stroke
				(width 0.1)
				(type default)
			)
			(layer "F.Fab")
		)
		(fp_line
			(start -0.12065 0.3048)
			(end -0.67945 0.3048)
			(stroke
				(width 0.1)
				(type default)
			)
			(layer "F.Fab")
		)
		(fp_line
			(start -0.67945 0.3048)
			(end -0.67945 -0.305054)
			(stroke
				(width 0.1)
				(type default)
			)
			(layer "F.Fab")
		)
		(pad "1" smd circle
			(at -0.40005 0 90)
			(size 0 0)
			(layers "F.Cu" "F.Mask" "F.Paste")
			(net "JTAG_DBP_TDI")
		)
		(pad "2" smd circle
			(at 0.40005 0 90)
			(size 0 0)
			(layers "F.Cu" "F.Mask" "F.Paste")
			(net "JTAG_DBP_FB_TDI")
		)
	)
)
